(kicad_pcb
	(version 20260206)
	(generator "pcbnew")
	(generator_version "10.0")
	(general
		(thickness 1.6)
		(legacy_teardrops no)
	)
	(paper "A4")
	(title_block
		(title "04192023_DAF0TMB3IC0_F0TG_MB_C_brd_V02_OCP.brd")
		(comment 1 "Grand Teton / footprints 6205-6211 of 8354")
	)
	(layers
		(0 "F.Cu" signal "TOP")
		(4 "In1.Cu" signal "GND")
		(6 "In2.Cu" signal "IN1")
		(8 "In3.Cu" signal "GND1")
		(10 "In4.Cu" signal "IN2")
		(12 "In5.Cu" signal "GND2")
		(14 "In6.Cu" signal "IN3")
		(16 "In7.Cu" signal "GND3")
		(18 "In8.Cu" signal "VCC")
		(20 "In9.Cu" signal "VCC1")
		(22 "In10.Cu" signal "GND4")
		(24 "In11.Cu" signal "IN4")
		(26 "In12.Cu" signal "GND5")
		(28 "In13.Cu" signal "IN5")
		(30 "In14.Cu" signal "GND6")
		(32 "In15.Cu" signal "IN6")
		(34 "In16.Cu" signal "GND7")
		(2 "B.Cu" signal "BOTTOM")
		(9 "F.Adhes" user "F.Adhesive")
		(11 "B.Adhes" user "B.Adhesive")
		(13 "F.Paste" user "Package Geometry/Pastemask Top")
		(15 "B.Paste" user "Package Geometry/Pastemask Bottom")
		(5 "F.SilkS" user "Ref Des/Silkscreen Top")
		(7 "B.SilkS" user "Ref Des/Silkscreen Bottom")
		(1 "F.Mask" user "Board Geometry/Soldermask Top")
		(3 "B.Mask" user "Board Geometry/Soldermask Bottom")
		(17 "Dwgs.User" user "User.Drawings")
		(19 "Cmts.User" user "User.Comments")
		(21 "Eco1.User" user "User.Eco1")
		(23 "Eco2.User" user "User.Eco2")
		(25 "Edge.Cuts" user "Board Geometry/Outline")
		(27 "Margin" user)
		(31 "F.CrtYd" user "Package Geometry/Place Bound Top")
		(29 "B.CrtYd" user "Package Geometry/Place Bound Bottom")
		(35 "F.Fab" user "Ref Des/Assembly Top")
		(33 "B.Fab" user "Ref Des/Assembly Bottom")
	)
	(footprint ""
		(layer "B.Cu")
		(at 365.836454 -250.89231)
		(property "Reference" "C2566"
			(at 0 0 0)
			(layer "B.SilkS")
			(hide yes)
			(effects
				(font
					(size 1.27 1.27)
				)
				(justify mirror)
			)
		)
		(property "Value" ""
			(at 0 0 0)
			(layer "B.Fab")
			(effects
				(font
					(size 1.27 1.27)
				)
				(justify mirror)
			)
		)
		(duplicate_pad_numbers_are_jumpers no)
		(fp_line
			(start -0.7874 -0.4064)
			(end -0.7874 0.4064)
			(stroke
				(width 0.1524)
				(type default)
			)
			(layer "B.SilkS")
		)
		(fp_line
			(start -0.7874 0.4064)
			(end 0.7874 0.4064)
			(stroke
				(width 0.1524)
				(type default)
			)
			(layer "B.SilkS")
		)
		(fp_line
			(start 0.7874 -0.4064)
			(end -0.7874 -0.4064)
			(stroke
				(width 0.1524)
				(type default)
			)
			(layer "B.SilkS")
		)
		(fp_line
			(start 0.7874 0.4064)
			(end 0.7874 -0.4064)
			(stroke
				(width 0.1524)
				(type default)
			)
			(layer "B.SilkS")
		)
		(fp_line
			(start -0.67945 -0.3048)
			(end -0.67945 0.3048)
			(stroke
				(width 0.1)
				(type default)
			)
			(layer "B.Fab")
		)
		(fp_line
			(start -0.67945 0.3048)
			(end -0.120396 0.3048)
			(stroke
				(width 0.1)
				(type default)
			)
			(layer "B.Fab")
		)
		(fp_line
			(start -0.12065 -0.3048)
			(end -0.67945 -0.3048)
			(stroke
				(width 0.1)
				(type default)
			)
			(layer "B.Fab")
		)
		(fp_line
			(start -0.12065 -0.2794)
			(end -0.12065 -0.3048)
			(stroke
				(width 0.1)
				(type default)
			)
			(layer "B.Fab")
		)
		(fp_line
			(start -0.120396 0.2794)
			(end 0.12065 0.2794)
			(stroke
				(width 0.1)
				(type default)
			)
			(layer "B.Fab")
		)
		(fp_line
			(start -0.120396 0.3048)
			(end -0.120396 0.2794)
			(stroke
				(width 0.1)
				(type default)
			)
			(layer "B.Fab")
		)
		(fp_line
			(start 0.12065 -0.305054)
			(end 0.12065 -0.2794)
			(stroke
				(width 0.1)
				(type default)
			)
			(layer "B.Fab")
		)
		(fp_line
			(start 0.12065 -0.2794)
			(end -0.12065 -0.2794)
			(stroke
				(width 0.1)
				(type default)
			)
			(layer "B.Fab")
		)
		(fp_line
			(start 0.12065 0.2794)
			(end 0.12065 0.3048)
			(stroke
				(width 0.1)
				(type default)
			)
			(layer "B.Fab")
		)
		(fp_line
			(start 0.12065 0.3048)
			(end 0.67945 0.3048)
			(stroke
				(width 0.1)
				(type default)
			)
			(layer "B.Fab")
		)
		(fp_line
			(start 0.67945 -0.305054)
			(end 0.12065 -0.305054)
			(stroke
				(width 0.1)
				(type default)
			)
			(layer "B.Fab")
		)
		(fp_line
			(start 0.67945 0.3048)
			(end 0.67945 -0.305054)
			(stroke
				(width 0.1)
				(type default)
			)
			(layer "B.Fab")
		)
		(pad "1" smd circle
			(at 0.40005 0 180)
			(size 0 0)
			(layers "B.Cu" "B.Mask" "B.Paste")
			(net "PVDDCR_SOC_P0")
		)
		(pad "2" smd circle
			(at -0.40005 0 180)
			(size 0 0)
			(layers "B.Cu" "B.Mask" "B.Paste")
			(net "GND")
		)
	)
	(footprint ""
		(layer "B.Cu")
		(at 296.479722 -194.88531 180)
		(property "Reference" "R761"
			(at 0 0 0)
			(layer "B.SilkS")
			(hide yes)
			(effects
				(font
					(size 1.27 1.27)
				)
				(justify mirror)
			)
		)
		(property "Value" ""
			(at 0 0 0)
			(layer "B.Fab")
			(effects
				(font
					(size 1.27 1.27)
				)
				(justify mirror)
			)
		)
		(duplicate_pad_numbers_are_jumpers no)
		(fp_line
			(start 0.7874 0.4064)
			(end 0.7874 -0.4064)
			(stroke
				(width 0.1524)
				(type default)
			)
			(layer "B.SilkS")
		)
		(fp_line
			(start 0.7874 -0.4064)
			(end -0.7874 -0.4064)
			(stroke
				(width 0.1524)
				(type default)
			)
			(layer "B.SilkS")
		)
		(fp_line
			(start -0.7874 0.4064)
			(end 0.7874 0.4064)
			(stroke
				(width 0.1524)
				(type default)
			)
			(layer "B.SilkS")
		)
		(fp_line
			(start -0.7874 -0.4064)
			(end -0.7874 0.4064)
			(stroke
				(width 0.1524)
				(type default)
			)
			(layer "B.SilkS")
		)
		(fp_line
			(start 0.67945 0.3048)
			(end 0.67945 -0.305054)
			(stroke
				(width 0.1)
				(type default)
			)
			(layer "B.Fab")
		)
		(fp_line
			(start 0.67945 -0.305054)
			(end 0.12065 -0.305054)
			(stroke
				(width 0.1)
				(type default)
			)
			(layer "B.Fab")
		)
		(fp_line
			(start 0.12065 0.3048)
			(end 0.67945 0.3048)
			(stroke
				(width 0.1)
				(type default)
			)
			(layer "B.Fab")
		)
		(fp_line
			(start 0.12065 0.2794)
			(end 0.12065 0.3048)
			(stroke
				(width 0.1)
				(type default)
			)
			(layer "B.Fab")
		)
		(fp_line
			(start 0.12065 -0.2794)
			(end -0.12065 -0.2794)
			(stroke
				(width 0.1)
				(type default)
			)
			(layer "B.Fab")
		)
		(fp_line
			(start 0.12065 -0.305054)
			(end 0.12065 -0.2794)
			(stroke
				(width 0.1)
				(type default)
			)
			(layer "B.Fab")
		)
		(fp_line
			(start -0.120396 0.3048)
			(end -0.120396 0.2794)
			(stroke
				(width 0.1)
				(type default)
			)
			(layer "B.Fab")
		)
		(fp_line
			(start -0.120396 0.2794)
			(end 0.12065 0.2794)
			(stroke
				(width 0.1)
				(type default)
			)
			(layer "B.Fab")
		)
		(fp_line
			(start -0.12065 -0.2794)
			(end -0.12065 -0.3048)
			(stroke
				(width 0.1)
				(type default)
			)
			(layer "B.Fab")
		)
		(fp_line
			(start -0.12065 -0.3048)
			(end -0.67945 -0.3048)
			(stroke
				(width 0.1)
				(type default)
			)
			(layer "B.Fab")
		)
		(fp_line
			(start -0.67945 0.3048)
			(end -0.120396 0.3048)
			(stroke
				(width 0.1)
				(type default)
			)
			(layer "B.Fab")
		)
		(fp_line
			(start -0.67945 -0.3048)
			(end -0.67945 0.3048)
			(stroke
				(width 0.1)
				(type default)
			)
			(layer "B.Fab")
		)
		(pad "1" smd circle
			(at 0.40005 0)
			(size 0 0)
			(layers "B.Cu" "B.Mask" "B.Paste")
			(net "PD_CHB_CPU0_DIMM_SAA")
		)
		(pad "2" smd circle
			(at -0.40005 0)
			(size 0 0)
			(layers "B.Cu" "B.Mask" "B.Paste")
			(net "GND")
		)
	)
	(footprint ""
		(layer "B.Cu")
		(at 287.933384 -337.984846 -90)
		(property "Reference" "PC190_3"
			(at 0 0 90)
			(layer "B.SilkS")
			(hide yes)
			(effects
				(font
					(size 1.27 1.27)
				)
				(justify mirror)
			)
		)
		(property "Value" ""
			(at 0 0 90)
			(layer "B.Fab")
			(effects
				(font
					(size 1.27 1.27)
				)
				(justify mirror)
			)
		)
		(duplicate_pad_numbers_are_jumpers no)
		(fp_line
			(start -1.524 0.762)
			(end 1.524 0.762)
			(stroke
				(width 0.1524)
				(type default)
			)
			(layer "B.SilkS")
		)
		(fp_line
			(start 1.524 0.762)
			(end 1.524 -0.762)
			(stroke
				(width 0.1524)
				(type default)
			)
			(layer "B.SilkS")
		)
		(fp_line
			(start -1.524 -0.762)
			(end -1.524 0.762)
			(stroke
				(width 0.1524)
				(type default)
			)
			(layer "B.SilkS")
		)
		(fp_line
			(start 1.524 -0.762)
			(end -1.524 -0.762)
			(stroke
				(width 0.1524)
				(type default)
			)
			(layer "B.SilkS")
		)
		(fp_line
			(start -1.1049 0.724916)
			(end -1.1049 -0.724916)
			(stroke
				(width 0.1)
				(type default)
			)
			(layer "B.Fab")
		)
		(fp_line
			(start 1.1049 0.724916)
			(end -1.1049 0.724916)
			(stroke
				(width 0.1)
				(type default)
			)
			(layer "B.Fab")
		)
		(fp_line
			(start -1.1049 -0.724916)
			(end 1.1049 -0.724916)
			(stroke
				(width 0.1)
				(type default)
			)
			(layer "B.Fab")
		)
		(fp_line
			(start 1.1049 -0.724916)
			(end 1.1049 0.724916)
			(stroke
				(width 0.1)
				(type default)
			)
			(layer "B.Fab")
		)
		(pad "1" smd rect
			(at 0.889 0 270)
			(size 1.016 1.27)
			(layers "B.Cu" "B.Mask" "B.Paste")
			(net "PVDDIO_P0")
		)
		(pad "2" smd rect
			(at -0.889 0 270)
			(size 1.016 1.27)
			(layers "B.Cu" "B.Mask" "B.Paste")
			(net "GND")
		)
	)
	(footprint ""
		(layer "B.Cu")
		(at 172.312838 -419.206426 180)
		(property "Reference" "R2807"
			(at 0 0 0)
			(layer "B.SilkS")
			(hide yes)
			(effects
				(font
					(size 1.27 1.27)
				)
				(justify mirror)
			)
		)
		(property "Value" ""
			(at 0 0 0)
			(layer "B.Fab")
			(effects
				(font
					(size 1.27 1.27)
				)
				(justify mirror)
			)
		)
		(duplicate_pad_numbers_are_jumpers no)
		(fp_line
			(start 0.7874 0.4064)
			(end 0.7874 -0.4064)
			(stroke
				(width 0.1524)
				(type default)
			)
			(layer "B.SilkS")
		)
		(fp_line
			(start 0.7874 -0.4064)
			(end -0.7874 -0.4064)
			(stroke
				(width 0.1524)
				(type default)
			)
			(layer "B.SilkS")
		)
		(fp_line
			(start -0.7874 0.4064)
			(end 0.7874 0.4064)
			(stroke
				(width 0.1524)
				(type default)
			)
			(layer "B.SilkS")
		)
		(fp_line
			(start -0.7874 -0.4064)
			(end -0.7874 0.4064)
			(stroke
				(width 0.1524)
				(type default)
			)
			(layer "B.SilkS")
		)
		(fp_line
			(start 0.67945 0.3048)
			(end 0.67945 -0.305054)
			(stroke
				(width 0.1)
				(type default)
			)
			(layer "B.Fab")
		)
		(fp_line
			(start 0.67945 -0.305054)
			(end 0.12065 -0.305054)
			(stroke
				(width 0.1)
				(type default)
			)
			(layer "B.Fab")
		)
		(fp_line
			(start 0.12065 0.3048)
			(end 0.67945 0.3048)
			(stroke
				(width 0.1)
				(type default)
			)
			(layer "B.Fab")
		)
		(fp_line
			(start 0.12065 0.2794)
			(end 0.12065 0.3048)
			(stroke
				(width 0.1)
				(type default)
			)
			(layer "B.Fab")
		)
		(fp_line
			(start 0.12065 -0.2794)
			(end -0.12065 -0.2794)
			(stroke
				(width 0.1)
				(type default)
			)
			(layer "B.Fab")
		)
		(fp_line
			(start 0.12065 -0.305054)
			(end 0.12065 -0.2794)
			(stroke
				(width 0.1)
				(type default)
			)
			(layer "B.Fab")
		)
		(fp_line
			(start -0.120396 0.3048)
			(end -0.120396 0.2794)
			(stroke
				(width 0.1)
				(type default)
			)
			(layer "B.Fab")
		)
		(fp_line
			(start -0.120396 0.2794)
			(end 0.12065 0.2794)
			(stroke
				(width 0.1)
				(type default)
			)
			(layer "B.Fab")
		)
		(fp_line
			(start -0.12065 -0.2794)
			(end -0.12065 -0.3048)
			(stroke
				(width 0.1)
				(type default)
			)
			(layer "B.Fab")
		)
		(fp_line
			(start -0.12065 -0.3048)
			(end -0.67945 -0.3048)
			(stroke
				(width 0.1)
				(type default)
			)
			(layer "B.Fab")
		)
		(fp_line
			(start -0.67945 0.3048)
			(end -0.120396 0.3048)
			(stroke
				(width 0.1)
				(type default)
			)
			(layer "B.Fab")
		)
		(fp_line
			(start -0.67945 -0.3048)
			(end -0.67945 0.3048)
			(stroke
				(width 0.1)
				(type default)
			)
			(layer "B.Fab")
		)
		(pad "1" smd circle
			(at 0.40005 0)
			(size 0 0)
			(layers "B.Cu" "B.Mask" "B.Paste")
			(net "P3V3_AUX")
		)
		(pad "2" smd circle
			(at -0.40005 0)
			(size 0 0)
			(layers "B.Cu" "B.Mask" "B.Paste")
			(net "SMB_FAN_3V3AUX_BUF_SDA")
		)
	)
	(footprint ""
		(layer "B.Cu")
		(at 9.271 -81.153 -90)
		(property "Reference" "C8002"
			(at 0 0 90)
			(layer "B.SilkS")
			(hide yes)
			(effects
				(font
					(size 1.27 1.27)
				)
				(justify mirror)
			)
		)
		(property "Value" ""
			(at 0 0 90)
			(layer "B.Fab")
			(effects
				(font
					(size 1.27 1.27)
				)
				(justify mirror)
			)
		)
		(duplicate_pad_numbers_are_jumpers no)
		(fp_line
			(start -0.7874 0.4064)
			(end 0.7874 0.4064)
			(stroke
				(width 0.1524)
				(type default)
			)
			(layer "B.SilkS")
		)
		(fp_line
			(start 0.7874 0.4064)
			(end 0.7874 -0.4064)
			(stroke
				(width 0.1524)
				(type default)
			)
			(layer "B.SilkS")
		)
		(fp_line
			(start -0.7874 -0.4064)
			(end -0.7874 0.4064)
			(stroke
				(width 0.1524)
				(type default)
			)
			(layer "B.SilkS")
		)
		(fp_line
			(start 0.7874 -0.4064)
			(end -0.7874 -0.4064)
			(stroke
				(width 0.1524)
				(type default)
			)
			(layer "B.SilkS")
		)
		(fp_line
			(start -0.67945 0.3048)
			(end -0.120396 0.3048)
			(stroke
				(width 0.1)
				(type default)
			)
			(layer "B.Fab")
		)
		(fp_line
			(start -0.120396 0.3048)
			(end -0.120396 0.2794)
			(stroke
				(width 0.1)
				(type default)
			)
			(layer "B.Fab")
		)
		(fp_line
			(start 0.12065 0.3048)
			(end 0.67945 0.3048)
			(stroke
				(width 0.1)
				(type default)
			)
			(layer "B.Fab")
		)
		(fp_line
			(start 0.67945 0.3048)
			(end 0.67945 -0.305054)
			(stroke
				(width 0.1)
				(type default)
			)
			(layer "B.Fab")
		)
		(fp_line
			(start -0.120396 0.2794)
			(end 0.12065 0.2794)
			(stroke
				(width 0.1)
				(type default)
			)
			(layer "B.Fab")
		)
		(fp_line
			(start 0.12065 0.2794)
			(end 0.12065 0.3048)
			(stroke
				(width 0.1)
				(type default)
			)
			(layer "B.Fab")
		)
		(fp_line
			(start -0.12065 -0.2794)
			(end -0.12065 -0.3048)
			(stroke
				(width 0.1)
				(type default)
			)
			(layer "B.Fab")
		)
		(fp_line
			(start 0.12065 -0.2794)
			(end -0.12065 -0.2794)
			(stroke
				(width 0.1)
				(type default)
			)
			(layer "B.Fab")
		)
		(fp_line
			(start -0.67945 -0.3048)
			(end -0.67945 0.3048)
			(stroke
				(width 0.1)
				(type default)
			)
			(layer "B.Fab")
		)
		(fp_line
			(start -0.12065 -0.3048)
			(end -0.67945 -0.3048)
			(stroke
				(width 0.1)
				(type default)
			)
			(layer "B.Fab")
		)
		(fp_line
			(start 0.12065 -0.305054)
			(end 0.12065 -0.2794)
			(stroke
				(width 0.1)
				(type default)
			)
			(layer "B.Fab")
		)
		(fp_line
			(start 0.67945 -0.305054)
			(end 0.12065 -0.305054)
			(stroke
				(width 0.1)
				(type default)
			)
			(layer "B.Fab")
		)
		(pad "1" smd circle
			(at 0.40005 0 90)
			(size 0 0)
			(layers "B.Cu" "B.Mask" "B.Paste")
			(net "OCP_SFF_PRSNT23_R1_N")
		)
		(pad "2" smd circle
			(at -0.40005 0 90)
			(size 0 0)
			(layers "B.Cu" "B.Mask" "B.Paste")
			(net "GND")
		)
	)
	(footprint ""
		(layer "B.Cu")
		(at 446.253616 -397.05407 90)
		(property "Reference" "PC6556_1"
			(at 0 0 90)
			(layer "B.SilkS")
			(hide yes)
			(effects
				(font
					(size 1.27 1.27)
				)
				(justify mirror)
			)
		)
		(property "Value" ""
			(at 0 0 90)
			(layer "B.Fab")
			(effects
				(font
					(size 1.27 1.27)
				)
				(justify mirror)
			)
		)
		(duplicate_pad_numbers_are_jumpers no)
		(fp_line
			(start 1.524 -0.762)
			(end -1.524 -0.762)
			(stroke
				(width 0.1524)
				(type default)
			)
			(layer "B.SilkS")
		)
		(fp_line
			(start -1.524 -0.762)
			(end -1.524 0.762)
			(stroke
				(width 0.1524)
				(type default)
			)
			(layer "B.SilkS")
		)
		(fp_line
			(start 1.524 0.762)
			(end 1.524 -0.762)
			(stroke
				(width 0.1524)
				(type default)
			)
			(layer "B.SilkS")
		)
		(fp_line
			(start -1.524 0.762)
			(end 1.524 0.762)
			(stroke
				(width 0.1524)
				(type default)
			)
			(layer "B.SilkS")
		)
		(fp_line
			(start 1.1049 -0.724916)
			(end 1.1049 0.724916)
			(stroke
				(width 0.1)
				(type default)
			)
			(layer "B.Fab")
		)
		(fp_line
			(start -1.1049 -0.724916)
			(end 1.1049 -0.724916)
			(stroke
				(width 0.1)
				(type default)
			)
			(layer "B.Fab")
		)
		(fp_line
			(start 1.1049 0.724916)
			(end -1.1049 0.724916)
			(stroke
				(width 0.1)
				(type default)
			)
			(layer "B.Fab")
		)
		(fp_line
			(start -1.1049 0.724916)
			(end -1.1049 -0.724916)
			(stroke
				(width 0.1)
				(type default)
			)
			(layer "B.Fab")
		)
		(pad "1" smd rect
			(at 0.889 0 90)
			(size 1.016 1.27)
			(layers "B.Cu" "B.Mask" "B.Paste")
			(net "SW_P12V_AUX_P0V9_RETIMER_CPU0_FLT")
		)
		(pad "2" smd rect
			(at -0.889 0 90)
			(size 1.016 1.27)
			(layers "B.Cu" "B.Mask" "B.Paste")
			(net "GND")
		)
	)
	(footprint ""
		(layer "B.Cu")
		(at 159.615632 -193.148966 -90)
		(property "Reference" "R566"
			(at 0 0 90)
			(layer "B.SilkS")
			(hide yes)
			(effects
				(font
					(size 1.27 1.27)
				)
				(justify mirror)
			)
		)
		(property "Value" ""
			(at 0 0 90)
			(layer "B.Fab")
			(effects
				(font
					(size 1.27 1.27)
				)
				(justify mirror)
			)
		)
		(duplicate_pad_numbers_are_jumpers no)
		(fp_line
			(start -0.7874 0.4064)
			(end 0.7874 0.4064)
			(stroke
				(width 0.1524)
				(type default)
			)
			(layer "B.SilkS")
		)
		(fp_line
			(start 0.7874 0.4064)
			(end 0.7874 -0.4064)
			(stroke
				(width 0.1524)
				(type default)
			)
			(layer "B.SilkS")
		)
		(fp_line
			(start -0.7874 -0.4064)
			(end -0.7874 0.4064)
			(stroke
				(width 0.1524)
				(type default)
			)
			(layer "B.SilkS")
		)
		(fp_line
			(start 0.7874 -0.4064)
			(end -0.7874 -0.4064)
			(stroke
				(width 0.1524)
				(type default)
			)
			(layer "B.SilkS")
		)
		(fp_line
			(start -0.67945 0.3048)
			(end -0.120396 0.3048)
			(stroke
				(width 0.1)
				(type default)
			)
			(layer "B.Fab")
		)
		(fp_line
			(start -0.120396 0.3048)
			(end -0.120396 0.2794)
			(stroke
				(width 0.1)
				(type default)
			)
			(layer "B.Fab")
		)
		(fp_line
			(start 0.12065 0.3048)
			(end 0.67945 0.3048)
			(stroke
				(width 0.1)
				(type default)
			)
			(layer "B.Fab")
		)
		(fp_line
			(start 0.67945 0.3048)
			(end 0.67945 -0.305054)
			(stroke
				(width 0.1)
				(type default)
			)
			(layer "B.Fab")
		)
		(fp_line
			(start -0.120396 0.2794)
			(end 0.12065 0.2794)
			(stroke
				(width 0.1)
				(type default)
			)
			(layer "B.Fab")
		)
		(fp_line
			(start 0.12065 0.2794)
			(end 0.12065 0.3048)
			(stroke
				(width 0.1)
				(type default)
			)
			(layer "B.Fab")
		)
		(fp_line
			(start -0.12065 -0.2794)
			(end -0.12065 -0.3048)
			(stroke
				(width 0.1)
				(type default)
			)
			(layer "B.Fab")
		)
		(fp_line
			(start 0.12065 -0.2794)
			(end -0.12065 -0.2794)
			(stroke
				(width 0.1)
				(type default)
			)
			(layer "B.Fab")
		)
		(fp_line
			(start -0.67945 -0.3048)
			(end -0.67945 0.3048)
			(stroke
				(width 0.1)
				(type default)
			)
			(layer "B.Fab")
		)
		(fp_line
			(start -0.12065 -0.3048)
			(end -0.67945 -0.3048)
			(stroke
				(width 0.1)
				(type default)
			)
			(layer "B.Fab")
		)
		(fp_line
			(start 0.12065 -0.305054)
			(end 0.12065 -0.2794)
			(stroke
				(width 0.1)
				(type default)
			)
			(layer "B.Fab")
		)
		(fp_line
			(start 0.67945 -0.305054)
			(end 0.12065 -0.305054)
			(stroke
				(width 0.1)
				(type default)
			)
			(layer "B.Fab")
		)
		(pad "1" smd rect
			(at 0.40005 0 270)
			(size 0.4572 0.508)
			(layers "B.Cu" "B.Mask" "B.Paste")
			(net "I3C_1_SPD_DDRGL_CPU1_SCL")
		)
		(pad "2" smd rect
			(at -0.40005 0 270)
			(size 0.4572 0.508)
			(layers "B.Cu" "B.Mask" "B.Paste")
			(net "I3C_1_SPD_DDRGL_CPU1_R_SCL")
		)
	)
)
